# T6G (Grand Teton) — schematic netlist excerpt (pin names and nets, part order shuffled) for the footprints in the layout excerpt that follows; sources: Cadence DE-HDL packaged netlist, KiCad conversion of 04192023_DAF0TMB3IC0_F0TG_MB_C_brd_V02_OCP.brd

J17  SCONN288_DDR506112002KQ  IO  pkg DDR288S_1-1VXC  page 88
  VIN_BULK0  = P12V_MEM_CPU0
  RFU0  = NC
  VIN_MGMT  = P3V3_AUX
  HSCL  = I3C_SPD_DDRC_CPU0_SCL
  HSDA  = I3C_SPD_DDRC_CPU0_SDA
  VSS0  = GND
  DQ0_A  = M_C_CPU0_SA_DQ<0>
  VSS1  = GND
  DQ1_A  = M_C_CPU0_SA_DQ<1>
  VSS2  = GND
  DQS0_A_T  = M_C_CPU0_SA_DQS_DP<0>
  DQS0_A_C  = M_C_CPU0_SA_DQS_DN<0>
  VSS3  = GND
  DQ4_A  = M_C_CPU0_SA_DQ<4>
  VSS4  = GND
  DQ5_A  = M_C_CPU0_SA_DQ<5>
  VSS5  = GND
  DQ8_A  = M_C_CPU0_SA_DQ<8>
  VSS6  = GND
  DQ9_A  = M_C_CPU0_SA_DQ<9>
  VSS7  = GND
  DQS1_A_T  = M_C_CPU0_SA_DQS_DP<1>
  DQS1_A_C  = M_C_CPU0_SA_DQS_DN<1>
  VSS8  = GND
  DQ12_A  = M_C_CPU0_SA_DQ<12>
  VSS9  = GND
  DQ13_A  = M_C_CPU0_SA_DQ<13>
  VSS10  = GND
  DQ16_A  = M_C_CPU0_SA_DQ<16>
  VSS11  = GND
  DQ17_A  = M_C_CPU0_SA_DQ<17>
  VSS12  = GND
  DQS2_A_T  = M_C_CPU0_SA_DQS_DP<2>
  DQS2_A_C  = M_C_CPU0_SA_DQS_DN<2>
  VSS13  = GND
  DQ20_A  = M_C_CPU0_SA_DQ<20>
  VSS14  = GND
  DQ21_A  = M_C_CPU0_SA_DQ<21>
  VSS15  = GND
  DQ24_A  = M_C_CPU0_SA_DQ<24>
  VSS16  = GND
  DQ25_A  = M_C_CPU0_SA_DQ<25>
  VSS17  = GND
  DQS3_A_T  = M_C_CPU0_SA_DQS_DP<3>
  DQS3_A_C  = M_C_CPU0_SA_DQS_DN<3>
  VSS18  = GND
  DQ28_A  = M_C_CPU0_SA_DQ<28>
  VSS19  = GND
  DQ29_A  = M_C_CPU0_SA_DQ<29>
  VSS20  = GND
  CB0_A  = M_C_CPU0_SA_CB<0>
  VSS21  = GND
  CB1_A  = M_C_CPU0_SA_CB<1>
  VSS22  = GND
  DQS4_A_T  = M_C_CPU0_SA_DQS_DP<4>
  DQS4_A_C  = M_C_CPU0_SA_DQS_DN<4>
  VSS23  = GND
  CB4_A  = M_C_CPU0_SA_CB<4>
  VSS24  = GND
  CB5_A  = M_C_CPU0_SA_CB<5>
  VSS25  = GND
  ALERT_N  = M_C_CPU0_ALERT_N
  VSS26  = GND
  CS0_A_N  = M_C_CPU0_SA_CS_N<0>
  VSS27  = GND
  CA0_A  = M_C_CPU0_SA_CA<0>
  VSS28  = GND
  CA2_A  = M_C_CPU0_SA_CA<2>
  VSS29  = GND
  CA4_A  = M_C_CPU0_SA_CA<4>
  VSS30  = GND
  CA6_A  = M_C_CPU0_SA_CA<6>
  VSS31  = GND
  PAR_A  = M_C_CPU0_SA_PAR
  VSS32  = GND
  CA0_B  = M_C_CPU0_SB_CA<0>
  VSS33  = GND
  CA2_B  = M_C_CPU0_SB_CA<2>
  VSS34  = GND
  CA4_B  = M_C_CPU0_SB_CA<4>
  VSS35  = GND
  CA6_B  = M_C_CPU0_SB_CA<6>
  VSS36  = GND
  CS0_B_N  = M_C_CPU0_SB_CS_N<0>
  VSS37  = GND
  \lbd||rsp_a_n\  = M_C_CPU0_SA_RSP<0>
  \lbs||rsp_b_n\  = M_C_CPU0_SB_RSP<0>
  VSS38  = GND
  CB4_B  = M_C_CPU0_SB_CB<4>
  VSS39  = GND
  CB5_B  = M_C_CPU0_SB_CB<5>
  VSS40  = GND
  \dqs9_b_t||tdqs9_b_t||dbi4_b_n\  = M_C_CPU0_SB_DQS_DP<9>
  \dqs9_b_c||tdqs9_b_c\  = M_C_CPU0_SB_DQS_DN<9>
  VSS41  = GND
  CB0_B  = M_C_CPU0_SB_CB<0>
  VSS42  = GND
  CB1_B  = M_C_CPU0_SB_CB<1>
  VSS43  = GND
  DQ0_B  = M_C_CPU0_SB_DQ<0>
  VSS44  = GND
  DQ1_B  = M_C_CPU0_SB_DQ<1>
  VSS45  = GND
  DQS0_B_T  = M_C_CPU0_SB_DQS_DP<0>
  DQS0_B_C  = M_C_CPU0_SB_DQS_DN<0>
  VSS46  = GND
  DQ4_B  = M_C_CPU0_SB_DQ<4>
  VSS47  = GND
  DQ5_B  = M_C_CPU0_SB_DQ<5>
  VSS48  = GND
  DQ8_B  = M_C_CPU0_SB_DQ<8>
  VSS49  = GND
  DQ9_B  = M_C_CPU0_SB_DQ<9>
  VSS50  = GND
  DQS1_B_T  = M_C_CPU0_SB_DQS_DP<1>
  DQS1_B_C  = M_C_CPU0_SB_DQS_DN<1>
  VSS51  = GND
  DQ12_B  = M_C_CPU0_SB_DQ<12>
  VSS52  = GND
  DQ13_B  = M_C_CPU0_SB_DQ<13>
  VSS53  = GND
  DQ16_B  = M_C_CPU0_SB_DQ<16>
  VSS54  = GND
  DQ17_B  = M_C_CPU0_SB_DQ<17>
  VSS55  = GND
  DQS2_B_T  = M_C_CPU0_SB_DQS_DP<2>
  DQS2_B_C  = M_C_CPU0_SB_DQS_DN<2>
  VSS56  = GND
  DQ20_B  = M_C_CPU0_SB_DQ<20>
  VSS57  = GND
  DQ21_B  = M_C_CPU0_SB_DQ<21>
  VSS58  = GND
  DQ24_B  = M_C_CPU0_SB_DQ<24>
  VSS59  = GND
  DQ25_B  = M_C_CPU0_SB_DQ<25>
  VSS60  = GND
  DQS3_B_T  = M_C_CPU0_SB_DQS_DP<3>
  DQS3_B_C  = M_C_CPU0_SB_DQS_DN<3>
  VSS61  = GND
  DQ28_B  = M_C_CPU0_SB_DQ<28>
  VSS62  = GND
  DQ29_B  = M_C_CPU0_SB_DQ<29>
  VSS63  = GND
  RFU1  = NC
  VIN_BULK1  = P12V_MEM_CPU0
  VIN_BULK2  = P12V_MEM_CPU0
  \pwr_good||fail_n\  = PWRGD_CHC_CPU0_DIMM
  HAS  = PD_CHC_CPU0_DIMM_SAA
  RFU2  = NC
  RFU3  = NC
  VSS64  = GND
  DQ2_A  = M_C_CPU0_SA_DQ<2>
  VSS65  = GND
  DQ3_A  = M_C_CPU0_SA_DQ<3>
  VSS66  = GND
  \dqs5_a_c||tdqs5_a_c||dqs5_a_t||tdqs5_a_t\  = M_C_CPU0_SA_DQS_DN<5>
  \dqs5_a_t||tdqs5_a_t\  = M_C_CPU0_SA_DQS_DP<5>
  VSS67  = GND
  DQ6_A  = M_C_CPU0_SA_DQ<6>
  VSS68  = GND
  DQ7_A  = M_C_CPU0_SA_DQ<7>
  VSS69  = GND
  DQ10_A  = M_C_CPU0_SA_DQ<10>
  VSS70  = GND
  DQ11_A  = M_C_CPU0_SA_DQ<11>
  VSS71  = GND
  \dqs6_a_c||tdqs6_a_c||dqs6_a_t||tdqs6_a_t\  = M_C_CPU0_SA_DQS_DN<6>
  \dqs6_a_t||tdqs6_a_t\  = M_C_CPU0_SA_DQS_DP<6>
  VSS72  = GND
  DQ14_A  = M_C_CPU0_SA_DQ<14>
  VSS73  = GND
  DQ15_A  = M_C_CPU0_SA_DQ<15>
  VSS74  = GND
  DQ18_A  = M_C_CPU0_SA_DQ<18>
  VSS75  = GND
  DQ19_A  = M_C_CPU0_SA_DQ<19>
  VSS76  = GND
  \dqs7_a_c||tdqs7_a_c\  = M_C_CPU0_SA_DQS_DN<7>
  \dqs7_a_t||tdqs7_a_t\  = M_C_CPU0_SA_DQS_DP<7>
  VSS77  = GND
  DQ22_A  = M_C_CPU0_SA_DQ<22>
  VSS78  = GND
  DQ23_A  = M_C_CPU0_SA_DQ<23>
  VSS79  = GND
  DQ26_A  = M_C_CPU0_SA_DQ<26>
  VSS80  = GND
  DQ27_A  = M_C_CPU0_SA_DQ<27>
  VSS81  = GND
  \dqs8_a_c||tdqs8_a_c\  = M_C_CPU0_SA_DQS_DN<8>
  \dqs8_a_t||tdqs8_a_t\  = M_C_CPU0_SA_DQS_DP<8>
  VSS82  = GND
  DQ30_A  = M_C_CPU0_SA_DQ<30>
  VSS83  = GND
  DQ31_A  = M_C_CPU0_SA_DQ<31>
  VSS84  = GND
  CB2_A  = M_C_CPU0_SA_CB<2>
  VSS85  = GND
  CB3_A  = M_C_CPU0_SA_CB<3>
  VSS86  = GND
  \dqs9_a_c||tdqs9_a_c\  = M_C_CPU0_SA_DQS_DN<9>
  \dqs9_a_t||tdqs9_a_t\  = M_C_CPU0_SA_DQS_DP<9>
  VSS87  = GND
  CB6_A  = M_C_CPU0_SA_CB<6>
  VSS88  = GND
  CB7_A  = M_C_CPU0_SA_CB<7>
  VSS89  = GND
  RESET_N  = M_C_CPU0_RESET_N
  VSS90  = GND
  CS1_A_N  = M_C_CPU0_SA_CS_N<1>
  VSS91  = GND
  CA1_A  = M_C_CPU0_SA_CA<1>
  VSS92  = GND
  CA3_A  = M_C_CPU0_SA_CA<3>
  VSS93  = GND
  CA5_A  = M_C_CPU0_SA_CA<5>
  VSS94  = GND
  CK_T  = M_C_CPU0_CLK_DP<0>
  CK_C  = M_C_CPU0_CLK_DN<0>
  VSS95  = GND
  RFU4  = NC
  CA1_B  = M_C_CPU0_SB_CA<1>
  VSS96  = GND
  CA3_B  = M_C_CPU0_SB_CA<3>
  VSS97  = GND
  CA5_B  = M_C_CPU0_SB_CA<5>
  VSS98  = GND
  PAR_B  = M_C_CPU0_SB_PAR
  VSS99  = GND
  CS1_B_N  = M_C_CPU0_SB_CS_N<1>
  VSS100  = GND
  RFU5  = NC
  RFU6  = NC
  VSS101  = GND
  CB6_B  = M_C_CPU0_SB_CB<6>
  VSS102  = GND
  CB7_B  = M_C_CPU0_SB_CB<7>
  VSS103  = GND
  DQS4_B_C  = M_C_CPU0_SB_DQS_DN<4>
  DQS4_B_T  = M_C_CPU0_SB_DQS_DP<4>
  VSS104  = GND
  CB2_B  = M_C_CPU0_SB_CB<2>
  VSS105  = GND
  CB3_B  = M_C_CPU0_SB_CB<3>
  VSS106  = GND
  DQ2_B  = M_C_CPU0_SB_DQ<2>
  VSS107  = GND
  DQ3_B  = M_C_CPU0_SB_DQ<3>
  VSS108  = GND
  \dqs5_b_c||tdqs5_b_c\  = M_C_CPU0_SB_DQS_DN<5>
  \dqs5_b_t||tdqs5_b_t\  = M_C_CPU0_SB_DQS_DP<5>
  VSS109  = GND
  DQ6_B  = M_C_CPU0_SB_DQ<6>
  VSS110  = GND
  DQ7_B  = M_C_CPU0_SB_DQ<7>
  VSS111  = GND
  DQ10_B  = M_C_CPU0_SB_DQ<10>
  VSS112  = GND
  DQ11_B  = M_C_CPU0_SB_DQ<11>
  VSS113  = GND
  \dqs6_b_c||tdqs6_b_c\  = M_C_CPU0_SB_DQS_DN<6>
  \dqs6_b_t||tdqs6_b_t\  = M_C_CPU0_SB_DQS_DP<6>
  VSS114  = GND
  DQ14_B  = M_C_CPU0_SB_DQ<14>
  VSS115  = GND
  DQ15_B  = M_C_CPU0_SB_DQ<15>
  VSS116  = GND
  DQ18_B  = M_C_CPU0_SB_DQ<18>
  VSS117  = GND
  DQ19_B  = M_C_CPU0_SB_DQ<19>
  VSS118  = GND
  \dqs7_b_c||tdqs7_b_c\  = M_C_CPU0_SB_DQS_DN<7>
  \dqs7_b_t||tdqs7_b_t\  = M_C_CPU0_SB_DQS_DP<7>
  VSS119  = GND
  DQ22_B  = M_C_CPU0_SB_DQ<22>
  VSS120  = GND
  DQ23_B  = M_C_CPU0_SB_DQ<23>
  VSS121  = GND
  DQ26_B  = M_C_CPU0_SB_DQ<26>
  VSS122  = GND
  DQ27_B  = M_C_CPU0_SB_DQ<27>
  VSS123  = GND
  \dqs8_b_c||tdqs8_b_c\  = M_C_CPU0_SB_DQS_DN<8>
  \dqs8_b_t||tdqs8_b_t\  = M_C_CPU0_SB_DQS_DP<8>
  VSS124  = GND
  DQ30_B  = M_C_CPU0_SB_DQ<30>
  VSS125  = GND
  DQ31_B  = M_C_CPU0_SB_DQ<31>
  VSS126  = GND
  G1  = GND
  G2  = GND
  G3  = GND

(kicad_pcb
	(version 20260206)
	(generator "pcbnew")
	(generator_version "10.0")
	(general
		(thickness 1.6)
		(legacy_teardrops no)
	)
	(paper "A4")
	(title_block
		(title "04192023_DAF0TMB3IC0_F0TG_MB_C_brd_V02_OCP.brd")
		(comment 1 "Grand Teton / footprint 4167 of 8354 (J17), pads 277-291 of 291")
	)
	(layers
		(0 "F.Cu" signal "TOP")
		(4 "In1.Cu" signal "GND")
		(6 "In2.Cu" signal "IN1")
		(8 "In3.Cu" signal "GND1")
		(10 "In4.Cu" signal "IN2")
		(12 "In5.Cu" signal "GND2")
		(14 "In6.Cu" signal "IN3")
		(16 "In7.Cu" signal "GND3")
		(18 "In8.Cu" signal "VCC")
		(20 "In9.Cu" signal "VCC1")
		(22 "In10.Cu" signal "GND4")
		(24 "In11.Cu" signal "IN4")
		(26 "In12.Cu" signal "GND5")
		(28 "In13.Cu" signal "IN5")
		(30 "In14.Cu" signal "GND6")
		(32 "In15.Cu" signal "IN6")
		(34 "In16.Cu" signal "GND7")
		(2 "B.Cu" signal "BOTTOM")
		(9 "F.Adhes" user "F.Adhesive")
		(11 "B.Adhes" user "B.Adhesive")
		(13 "F.Paste" user "Package Geometry/Pastemask Top")
		(15 "B.Paste" user "Package Geometry/Pastemask Bottom")
		(5 "F.SilkS" user "Ref Des/Silkscreen Top")
		(7 "B.SilkS" user "Ref Des/Silkscreen Bottom")
		(1 "F.Mask" user "Board Geometry/Soldermask Top")
		(3 "B.Mask" user "Board Geometry/Soldermask Bottom")
		(17 "Dwgs.User" user "User.Drawings")
		(19 "Cmts.User" user "User.Comments")
		(21 "Eco1.User" user "User.Eco1")
		(23 "Eco2.User" user "User.Eco2")
		(25 "Edge.Cuts" user "Board Geometry/Outline")
		(27 "Margin" user)
		(31 "F.CrtYd" user "Package Geometry/Place Bound Top")
		(29 "B.CrtYd" user "Package Geometry/Place Bound Bottom")
		(35 "F.Fab" user "Ref Des/Assembly Top")
		(33 "B.Fab" user "Ref Des/Assembly Bottom")
	)
	(footprint ""
		(layer "F.Cu")
		(at 290.230052 -255.560068 180)
		(property "Reference" "J17"
			(at -2.2098 -81.984088 0)
			(unlocked yes)
			(layer "F.SilkS")
			(effects
				(font
					(size 0.7874 0.5842)
					(thickness 0.1524)
				)
			)
		)
		(property "Value" ""
			(at 0 0 180)
			(layer "F.Fab")
			(effects
				(font
					(size 1.27 1.27)
				)
			)
		)
		(duplicate_pad_numbers_are_jumpers no)
		(pad "277" smd rect
			(at 2.050034 53.975 90)
			(size 0.519938 1.4986)
			(layers "F.Cu" "F.Mask" "F.Paste")
			(net "GND")
		)
		(pad "278" smd rect
			(at 2.050034 54.824884 90)
			(size 0.519938 1.4986)
			(layers "F.Cu" "F.Mask" "F.Paste")
			(net "M_C_CPU0_SB_DQ<26>")
		)
		(pad "279" smd rect
			(at 2.050034 55.675022 90)
			(size 0.519938 1.4986)
			(layers "F.Cu" "F.Mask" "F.Paste")
			(net "GND")
		)
		(pad "280" smd rect
			(at 2.050034 56.524906 90)
			(size 0.519938 1.4986)
			(layers "F.Cu" "F.Mask" "F.Paste")
			(net "M_C_CPU0_SB_DQ<27>")
		)
		(pad "281" smd rect
			(at 2.050034 57.375044 90)
			(size 0.519938 1.4986)
			(layers "F.Cu" "F.Mask" "F.Paste")
			(net "GND")
		)
		(pad "282" smd rect
			(at 2.050034 58.224928 90)
			(size 0.519938 1.4986)
			(layers "F.Cu" "F.Mask" "F.Paste")
			(net "M_C_CPU0_SB_DQS_DN<8>")
		)
		(pad "283" smd rect
			(at 2.050034 59.075066 90)
			(size 0.519938 1.4986)
			(layers "F.Cu" "F.Mask" "F.Paste")
			(net "M_C_CPU0_SB_DQS_DP<8>")
		)
		(pad "284" smd rect
			(at 2.050034 59.92495 90)
			(size 0.519938 1.4986)
			(layers "F.Cu" "F.Mask" "F.Paste")
			(net "GND")
		)
		(pad "285" smd rect
			(at 2.050034 60.775088 90)
			(size 0.519938 1.4986)
			(layers "F.Cu" "F.Mask" "F.Paste")
			(net "M_C_CPU0_SB_DQ<30>")
		)
		(pad "286" smd rect
			(at 2.050034 61.624972 90)
			(size 0.519938 1.4986)
			(layers "F.Cu" "F.Mask" "F.Paste")
			(net "GND")
		)
		(pad "287" smd rect
			(at 2.050034 62.47511 90)
			(size 0.519938 1.4986)
			(layers "F.Cu" "F.Mask" "F.Paste")
			(net "M_C_CPU0_SB_DQ<31>")
		)
		(pad "288" smd rect
			(at 2.050034 63.324994 90)
			(size 0.519938 1.4986)
			(layers "F.Cu" "F.Mask" "F.Paste")
			(net "GND")
		)
		(pad "G1" thru_hole oval
			(at 0 -68.97497 90)
			(size 1.7272 3.4798)
			(drill oval 1.2192 2.4638)
			(layers "*.Cu" "*.Mask")
			(remove_unused_layers no)
			(net "GND")
			(clearance 0.127)
			(thermal_gap 0.127)
		)
		(pad "G2" thru_hole oval
			(at 0 3.875024 90)
			(size 1.7272 3.4798)
			(drill oval 1.2192 2.4638)
			(layers "*.Cu" "*.Mask")
			(remove_unused_layers no)
			(net "GND")
			(clearance 0.127)
			(thermal_gap 0.127)
		)
		(pad "G3" thru_hole oval
			(at 0 68.97497 90)
			(size 1.7272 3.4798)
			(drill oval 1.2192 2.4638)
			(layers "*.Cu" "*.Mask")
			(remove_unused_layers no)
			(net "GND")
			(clearance 0.127)
			(thermal_gap 0.127)
		)
	)
)
